(kicad_pcb
	(version 20241229)
	(generator "pcbnew")
	(generator_version "9.0")
	(general
		(thickness 1.711)
		(legacy_teardrops no)
	)
	(paper "A4")
	(title_block
		(title "Antmicro Baseboard for Jetson AGX Thor")
		(date "2026-02-18")
		(rev "1.1.0")
		(company "Antmicro Ltd")
		(comment 1 "www.antmicro.com")
		(comment 9 "footprints 1034-1037 of 1170")
	)
	(layers
		(0 "F.Cu" signal)
		(4 "In1.Cu" signal)
		(6 "In2.Cu" signal)
		(8 "In3.Cu" signal)
		(10 "In4.Cu" jumper)
		(12 "In5.Cu" signal)
		(14 "In6.Cu" signal)
		(16 "In7.Cu" signal)
		(18 "In8.Cu" signal)
		(2 "B.Cu" signal)
		(9 "F.Adhes" user "F.Adhesive")
		(11 "B.Adhes" user "B.Adhesive")
		(13 "F.Paste" user)
		(15 "B.Paste" user)
		(5 "F.SilkS" user "F.Silkscreen")
		(7 "B.SilkS" user "B.Silkscreen")
		(1 "F.Mask" user)
		(3 "B.Mask" user)
		(17 "Dwgs.User" user "User.Drawings")
		(19 "Cmts.User" user "User.Comments")
		(21 "Eco1.User" user "User.Eco1")
		(23 "Eco2.User" user "User.Eco2")
		(25 "Edge.Cuts" user)
		(27 "Margin" user)
		(31 "F.CrtYd" user "F.Courtyard")
		(29 "B.CrtYd" user "B.Courtyard")
		(35 "F.Fab" user)
		(33 "B.Fab" user)
	)
	(footprint "antmicro-footprints:SOD-523"
		(layer "B.Cu")
		(at 148.7 147 90)
		(property "Reference" "D1"
			(at -0.9 0.8 90)
			(layer "B.SilkS")
			(effects
				(font
					(size 0.7 0.7)
					(thickness 0.15)
				)
				(justify right top mirror)
			)
		)
		(property "Value" "RB521S30T1G"
			(at 0 -1.499 90)
			(layer "B.Fab")
			(effects
				(font
					(size 0.7 0.7)
					(thickness 0.15)
				)
				(justify right top mirror)
			)
		)
		(property "Datasheet" "https://www.onsemi.com/pdf/datasheet/rb521s30t1-d.pdf"
			(at 0 0 90)
			(layer "B.Fab")
			(hide yes)
			(effects
				(font
					(size 1.27 1.27)
					(thickness 0.15)
				)
				(justify mirror)
			)
		)
		(property "Description" "Small Signal Schottky Diode, Single, 30 V, 200 mA, 500 mV, 1 A, 125 °C"
			(at 0 0 90)
			(layer "B.Fab")
			(hide yes)
			(effects
				(font
					(size 1.27 1.27)
					(thickness 0.15)
				)
				(justify mirror)
			)
		)
		(property "MPN" "RB521S30T1G"
			(at 0 0 270)
			(unlocked yes)
			(layer "B.Fab")
			(hide yes)
			(effects
				(font
					(size 1 1)
					(thickness 0.15)
				)
				(justify mirror)
			)
		)
		(property "Manufacturer" "ON Semiconductor"
			(at 0 0 270)
			(unlocked yes)
			(layer "B.Fab")
			(hide yes)
			(effects
				(font
					(size 1 1)
					(thickness 0.15)
				)
				(justify mirror)
			)
		)
		(property "Author" "Antmicro"
			(at 0 0 270)
			(unlocked yes)
			(layer "B.Fab")
			(hide yes)
			(effects
				(font
					(size 1 1)
					(thickness 0.15)
				)
				(justify mirror)
			)
		)
		(property "License" "Apache-2.0"
			(at 0 0 270)
			(unlocked yes)
			(layer "B.Fab")
			(hide yes)
			(effects
				(font
					(size 1 1)
					(thickness 0.15)
				)
				(justify mirror)
			)
		)
		(sheetname "/SoM_Power/")
		(sheetfile "som_power.kicad_sch")
		(attr smd)
		(fp_line
			(start -0.35 0.5)
			(end -0.35 -0.5)
			(stroke
				(width 0.15)
				(type solid)
			)
			(layer "B.SilkS")
		)
		(fp_rect
			(start -1 0.6)
			(end 1 -0.6)
			(stroke
				(width 0.05)
				(type solid)
			)
			(fill no)
			(layer "B.CrtYd")
		)
		(fp_line
			(start -0.652 -0.423)
			(end 0.65 -0.423)
			(stroke
				(width 0.15)
				(type solid)
			)
			(layer "B.Fab")
		)
		(fp_line
			(start -0.652 -0.423)
			(end -0.652 0.425)
			(stroke
				(width 0.15)
				(type solid)
			)
			(layer "B.Fab")
		)
		(fp_line
			(start -0.35 0.4)
			(end -0.35 -0.4)
			(stroke
				(width 0.15)
				(type solid)
			)
			(layer "B.Fab")
		)
		(fp_line
			(start 0.65 0.425)
			(end 0.65 -0.423)
			(stroke
				(width 0.15)
				(type solid)
			)
			(layer "B.Fab")
		)
		(fp_line
			(start -0.652 0.425)
			(end 0.65 0.425)
			(stroke
				(width 0.15)
				(type solid)
			)
			(layer "B.Fab")
		)
		(fp_text user "Author: Antmicro"
			(at -1.276 -4.7 90)
			(layer "B.Fab")
			(effects
				(font
					(size 0.7 0.7)
					(thickness 0.15)
				)
				(justify right top mirror)
			)
		)
		(fp_text user "${REFERENCE}"
			(at -1.276 -3.499 90)
			(layer "B.Fab")
			(effects
				(font
					(size 0.7 0.7)
					(thickness 0.15)
				)
				(justify right top mirror)
			)
		)
		(fp_text user "License: Apache-2.0"
			(at -1.276 -5.9 90)
			(layer "B.Fab")
			(effects
				(font
					(size 0.7 0.7)
					(thickness 0.15)
				)
				(justify right top mirror)
			)
		)
		(pad "1" smd roundrect
			(at -0.701 0 90)
			(size 0.5 0.6)
			(layers "B.Cu" "B.Mask" "B.Paste")
			(roundrect_rratio 0.25)
			(net 32 "Net-(D1-C)")
			(pinfunction "C")
			(pintype "passive")
		)
		(pad "2" smd roundrect
			(at 0.699 0 90)
			(size 0.5 0.6)
			(layers "B.Cu" "B.Mask" "B.Paste")
			(roundrect_rratio 0.25)
			(net 4 "+3V3_AON")
			(pinfunction "A")
			(pintype "passive")
		)
	)
	(footprint "antmicro-footprints:C_0402_1005Metric"
		(layer "B.Cu")
		(at 110.25 104.5)
		(descr "Capacitor SMD 0402")
		(tags "capacitor SMD 0402")
		(property "Reference" "C186"
			(at -0.95 -0.4 0)
			(layer "B.SilkS")
			(effects
				(font
					(size 0.7 0.7)
					(thickness 0.15)
				)
				(justify left top mirror)
			)
		)
		(property "Value" "C_220n_0402"
			(at -1.022927 -2.155213 0)
			(layer "B.Fab")
			(effects
				(font
					(size 0.7 0.7)
					(thickness 0.15)
				)
				(justify right top mirror)
			)
		)
		(property "Datasheet" "https://www.yageo.com/en/Chart/Download/pdf/CC0402KRX5R6BB224"
			(at 0 0 0)
			(layer "B.Fab")
			(hide yes)
			(effects
				(font
					(size 1.27 1.27)
					(thickness 0.15)
				)
				(justify mirror)
			)
		)
		(property "Description" "SMD Multilayer Ceramic Capacitor, 0.22 µF, 10 V, 0402 [1005 Metric], ± 10%, X5R, CC Series"
			(at 0 0 0)
			(layer "B.Fab")
			(hide yes)
			(effects
				(font
					(size 1.27 1.27)
					(thickness 0.15)
				)
				(justify mirror)
			)
		)
		(property "MPN" "CC0402KRX5R6BB224"
			(at 0 0 0)
			(unlocked yes)
			(layer "B.Fab")
			(hide yes)
			(effects
				(font
					(size 1 1)
					(thickness 0.15)
				)
				(justify mirror)
			)
		)
		(property "Val" "220n"
			(at 0 0 0)
			(unlocked yes)
			(layer "B.Fab")
			(hide yes)
			(effects
				(font
					(size 1 1)
					(thickness 0.15)
				)
				(justify mirror)
			)
		)
		(property "Voltage" "25V"
			(at 0 0 0)
			(unlocked yes)
			(layer "B.Fab")
			(hide yes)
			(effects
				(font
					(size 1 1)
					(thickness 0.15)
				)
				(justify mirror)
			)
		)
		(property "Dielectric" "X7R"
			(at 0 0 0)
			(unlocked yes)
			(layer "B.Fab")
			(hide yes)
			(effects
				(font
					(size 1 1)
					(thickness 0.15)
				)
				(justify mirror)
			)
		)
		(property "Manufacturer" "YAGEO"
			(at 0 0 0)
			(unlocked yes)
			(layer "B.Fab")
			(hide yes)
			(effects
				(font
					(size 1 1)
					(thickness 0.15)
				)
				(justify mirror)
			)
		)
		(property "License" "Apache-2.0"
			(at 0 0 0)
			(unlocked yes)
			(layer "B.Fab")
			(hide yes)
			(effects
				(font
					(size 1 1)
					(thickness 0.15)
				)
				(justify mirror)
			)
		)
		(property "Author" "Antmicro"
			(at 0 0 0)
			(unlocked yes)
			(layer "B.Fab")
			(hide yes)
			(effects
				(font
					(size 1 1)
					(thickness 0.15)
				)
				(justify mirror)
			)
		)
		(property "Public" "False"
			(at 0 0 0)
			(unlocked yes)
			(layer "B.Fab")
			(hide yes)
			(effects
				(font
					(size 1 1)
					(thickness 0.15)
				)
				(justify mirror)
			)
		)
		(sheetname "/M.2/")
		(sheetfile "m2.kicad_sch")
		(attr smd)
		(fp_poly
			(pts
				(xy -0.925 0.47) (xy -0.925 -0.47) (xy 0.925 -0.47) (xy 0.925 0.47)
			)
			(stroke
				(width 0.05)
				(type default)
			)
			(fill no)
			(layer "B.CrtYd")
		)
		(fp_line
			(start -0.494 -0.248)
			(end -0.494 0.25)
			(stroke
				(width 0.15)
				(type solid)
			)
			(layer "B.Fab")
		)
		(fp_line
			(start -0.494 0.25)
			(end 0.504 0.25)
			(stroke
				(width 0.15)
				(type solid)
			)
			(layer "B.Fab")
		)
		(fp_line
			(start 0.504 -0.248)
			(end -0.494 -0.248)
			(stroke
				(width 0.15)
				(type solid)
			)
			(layer "B.Fab")
		)
		(fp_line
			(start 0.504 0.25)
			(end 0.504 -0.248)
			(stroke
				(width 0.15)
				(type solid)
			)
			(layer "B.Fab")
		)
		(fp_text user "License: Apache-2.0"
			(at -0.939 -5.799 0)
			(layer "B.Fab")
			(effects
				(font
					(size 0.7 0.7)
					(thickness 0.15)
				)
				(justify right top mirror)
			)
		)
		(fp_text user "${REFERENCE}"
			(at -0.939 -4.599 0)
			(layer "B.Fab")
			(effects
				(font
					(size 0.7 0.7)
					(thickness 0.15)
				)
				(justify right top mirror)
			)
		)
		(fp_text user "Author: Antmicro"
			(at -0.939 -3.399 0)
			(layer "B.Fab")
			(effects
				(font
					(size 0.7 0.7)
					(thickness 0.15)
				)
				(justify right top mirror)
			)
		)
		(pad "1" smd roundrect
			(at -0.48 0)
			(size 0.59 0.64)
			(layers "B.Cu" "B.Mask" "B.Paste")
			(roundrect_rratio 0.25)
			(net 418 "/M.2/PCIe_{C5x4}.TX1-")
			(pintype "passive")
		)
		(pad "2" smd roundrect
			(at 0.48 0)
			(size 0.59 0.64)
			(layers "B.Cu" "B.Mask" "B.Paste")
			(roundrect_rratio 0.25)
			(net 417 "/M.2/M2_M_PET1_N")
			(pintype "passive")
		)
	)
	(footprint "antmicro-footprints:R_0402_1005Metric"
		(layer "B.Cu")
		(at 124.6 134.95)
		(descr "Resistor SMD 0402")
		(tags "resistor SMD 0402")
		(property "Reference" "R264"
			(at -1.2 -5.55 0)
			(layer "B.SilkS")
			(effects
				(font
					(size 0.7 0.7)
					(thickness 0.15)
				)
				(justify right top mirror)
			)
		)
		(property "Value" "R_0R_0402"
			(at -1.011843 -1.772046 0)
			(layer "B.Fab")
			(effects
				(font
					(size 0.7 0.7)
					(thickness 0.15)
				)
				(justify right top mirror)
			)
		)
		(property "Datasheet" "https://industrial.panasonic.com/cdbs/www-data/pdf/RDA0000/AOA0000C301.pdf"
			(at 0 0 0)
			(layer "B.Fab")
			(hide yes)
			(effects
				(font
					(size 1.27 1.27)
					(thickness 0.15)
				)
				(justify mirror)
			)
		)
		(property "Description" "SMD Chip Resistor, Jumper, 0 ohm, 100 mW, 0402 [1005 Metric], Thick Film, General Purpose"
			(at 0 0 0)
			(layer "B.Fab")
			(hide yes)
			(effects
				(font
					(size 1.27 1.27)
					(thickness 0.15)
				)
				(justify mirror)
			)
		)
		(property "MPN" "ERJ2GE0R00X"
			(at 0 0 180)
			(unlocked yes)
			(layer "B.Fab")
			(hide yes)
			(effects
				(font
					(size 1 1)
					(thickness 0.15)
				)
				(justify mirror)
			)
		)
		(property "Manufacturer" "Panasonic"
			(at 0 0 180)
			(unlocked yes)
			(layer "B.Fab")
			(hide yes)
			(effects
				(font
					(size 1 1)
					(thickness 0.15)
				)
				(justify mirror)
			)
		)
		(property "License" "Apache-2.0"
			(at 0 0 180)
			(unlocked yes)
			(layer "B.Fab")
			(hide yes)
			(effects
				(font
					(size 1 1)
					(thickness 0.15)
				)
				(justify mirror)
			)
		)
		(property "Val" "0R"
			(at 0 0 180)
			(unlocked yes)
			(layer "B.Fab")
			(hide yes)
			(effects
				(font
					(size 1 1)
					(thickness 0.15)
				)
				(justify mirror)
			)
		)
		(property "Tolerance" "~"
			(at 0 0 180)
			(unlocked yes)
			(layer "B.Fab")
			(hide yes)
			(effects
				(font
					(size 1 1)
					(thickness 0.15)
				)
				(justify mirror)
			)
		)
		(property "Current" "1A"
			(at 0 0 180)
			(unlocked yes)
			(layer "B.Fab")
			(hide yes)
			(effects
				(font
					(size 1 1)
					(thickness 0.15)
				)
				(justify mirror)
			)
		)
		(property "Author" "Antmicro"
			(at 0 0 180)
			(unlocked yes)
			(layer "B.Fab")
			(hide yes)
			(effects
				(font
					(size 1 1)
					(thickness 0.15)
				)
				(justify mirror)
			)
		)
		(property "Public" "False"
			(at 0 0 180)
			(unlocked yes)
			(layer "B.Fab")
			(hide yes)
			(effects
				(font
					(size 1 1)
					(thickness 0.15)
				)
				(justify mirror)
			)
		)
		(sheetname "/M.2/")
		(sheetfile "m2.kicad_sch")
		(attr smd)
		(fp_poly
			(pts
				(xy -0.925 0.47) (xy 0.925 0.47) (xy 0.925 -0.47) (xy -0.925 -0.47)
			)
			(stroke
				(width 0.05)
				(type default)
			)
			(fill no)
			(layer "B.CrtYd")
		)
		(fp_poly
			(pts
				(xy -0.5 0.25) (xy 0.5 0.25) (xy 0.5 -0.25) (xy -0.5 -0.25)
			)
			(stroke
				(width 0.15)
				(type solid)
			)
			(fill no)
			(layer "B.Fab")
		)
		(fp_text user "License: Apache-2.0"
			(at -0.949999 -5.169 0)
			(layer "B.Fab")
			(effects
				(font
					(size 0.7 0.7)
					(thickness 0.15)
				)
				(justify right top mirror)
			)
		)
		(fp_text user "Author: Antmicro"
			(at -0.95 -4.169 0)
			(layer "B.Fab")
			(effects
				(font
					(size 0.7 0.7)
					(thickness 0.15)
				)
				(justify right top mirror)
			)
		)
		(fp_text user "${REFERENCE}"
			(at -0.95 -3.168 0)
			(layer "B.Fab")
			(effects
				(font
					(size 0.7 0.7)
					(thickness 0.15)
				)
				(justify right top mirror)
			)
		)
		(pad "1" smd roundrect
			(at -0.48 0)
			(size 0.59 0.64)
			(layers "B.Cu" "B.Mask" "B.Paste")
			(roundrect_rratio 0.25)
			(net 244 "/M.2/M2_E_W_DIS_1")
			(pintype "passive")
		)
		(pad "2" smd roundrect
			(at 0.48 0)
			(size 0.59 0.64)
			(layers "B.Cu" "B.Mask" "B.Paste")
			(roundrect_rratio 0.25)
			(net 1113 "/M.2/M2_E.W_DIS_1")
			(pintype "passive")
		)
	)
	(footprint "antmicro-footprints:Vishay_PowerPAK_1212-8_Single"
		(layer "B.Cu")
		(at 183.08 84.307 90)
		(descr "PowerPAK 1212-8 Single")
		(tags "Vishay PowerPAK 1212-8 Single")
		(property "Reference" "Q24"
			(at -0.093 1.92 90)
			(layer "B.SilkS")
			(effects
				(font
					(size 0.7 0.7)
					(thickness 0.15)
				)
				(justify right top mirror)
			)
		)
		(property "Value" "SISS05DN-T1-GE3"
			(at 0 -2.7 90)
			(layer "B.Fab")
			(effects
				(font
					(size 0.7 0.7)
					(thickness 0.15)
				)
				(justify right top mirror)
			)
		)
		(property "Datasheet" "https://www.vishay.com/docs/77029/siss05dn.pdf"
			(at 0 0 90)
			(layer "B.Fab")
			(hide yes)
			(effects
				(font
					(size 1.27 1.27)
					(thickness 0.15)
				)
				(justify mirror)
			)
		)
		(property "Description" "Power MOSFET, P Channel, 30 V, 108 A, 0.0035 ohm, PowerPAK 1212, Surface Mount"
			(at 0 0 90)
			(layer "B.Fab")
			(hide yes)
			(effects
				(font
					(size 1.27 1.27)
					(thickness 0.15)
				)
				(justify mirror)
			)
		)
		(property "MPN" "SISS05DN-T1-GE3"
			(at 0 0 270)
			(unlocked yes)
			(layer "B.Fab")
			(hide yes)
			(effects
				(font
					(size 1 1)
					(thickness 0.15)
				)
				(justify mirror)
			)
		)
		(property "Manufacturer" "Vishay"
			(at 0 0 270)
			(unlocked yes)
			(layer "B.Fab")
			(hide yes)
			(effects
				(font
					(size 1 1)
					(thickness 0.15)
				)
				(justify mirror)
			)
		)
		(property "Author" "Antmicro"
			(at 0 0 270)
			(unlocked yes)
			(layer "B.Fab")
			(hide yes)
			(effects
				(font
					(size 1 1)
					(thickness 0.15)
				)
				(justify mirror)
			)
		)
		(property "License" "Apache-2.0"
			(at 0 0 270)
			(unlocked yes)
			(layer "B.Fab")
			(hide yes)
			(effects
				(font
					(size 1 1)
					(thickness 0.15)
				)
				(justify mirror)
			)
		)
		(sheetname "/Power/")
		(sheetfile "power.kicad_sch")
		(attr smd)
		(fp_line
			(start -1.635 -1.634)
			(end 1.634 -1.634)
			(stroke
				(width 0.15)
				(type solid)
			)
			(layer "B.SilkS")
		)
		(fp_line
			(start 1.634 -1.3)
			(end 1.634 -1.634)
			(stroke
				(width 0.15)
				(type solid)
			)
			(layer "B.SilkS")
		)
		(fp_line
			(start -1.635 -1.3)
			(end -1.635 -1.634)
			(stroke
				(width 0.15)
				(type solid)
			)
			(layer "B.SilkS")
		)
		(fp_line
			(start 1.648 1.651)
			(end 1.648 1.317)
			(stroke
				(width 0.15)
				(type solid)
			)
			(layer "B.SilkS")
		)
		(fp_line
			(start -1.651 1.651)
			(end -1.651 1.317)
			(stroke
				(width 0.15)
				(type solid)
			)
			(layer "B.SilkS")
		)
		(fp_line
			(start -1.651 1.651)
			(end 1.648 1.651)
			(stroke
				(width 0.15)
				(type solid)
			)
			(layer "B.SilkS")
		)
		(fp_circle
			(center -1.9 1.4)
			(end -1.85 1.4)
			(stroke
				(width 0.15)
				(type solid)
			)
			(fill yes)
			(layer "B.SilkS")
		)
		(fp_rect
			(start -2 1.8)
			(end 2 -1.798)
			(stroke
				(width 0.05)
				(type solid)
			)
			(fill no)
			(layer "B.CrtYd")
		)
		(fp_line
			(start -1.6425 1.4175)
			(end -1.4175 1.6425)
			(stroke
				(width 0.15)
				(type solid)
			)
			(layer "B.Fab")
		)
		(fp_rect
			(start -1.651 1.651)
			(end 1.648 -1.648)
			(stroke
				(width 0.15)
				(type solid)
			)
			(fill no)
			(layer "B.Fab")
		)
		(fp_text user "License: Apache-2.0"
			(at -8 -7.1 90)
			(layer "B.Fab")
			(effects
				(font
					(size 0.7 0.7)
					(thickness 0.15)
				)
				(justify right top mirror)
			)
		)
		(fp_text user "Author: Antmicro"
			(at -8 -5.9 90)
			(layer "B.Fab")
			(effects
				(font
					(size 0.7 0.7)
					(thickness 0.15)
				)
				(justify right top mirror)
			)
		)
		(fp_text user "${REFERENCE}"
			(at -8 -4.7 90)
			(layer "B.Fab")
			(effects
				(font
					(size 0.7 0.7)
					(thickness 0.15)
				)
				(justify right top mirror)
			)
		)
		(pad "1" smd rect
			(at -1.436 0.99 90)
			(size 0.99 0.405)
			(layers "B.Cu" "B.Mask" "B.Paste")
			(net 522 "/Power/USBPD1_HV")
			(pinfunction "S")
			(pintype "passive")
		)
		(pad "2" smd rect
			(at -1.436 0.332 90)
			(size 0.99 0.405)
			(layers "B.Cu" "B.Mask" "B.Paste")
			(net 522 "/Power/USBPD1_HV")
			(pinfunction "S")
			(pintype "passive")
		)
		(pad "3" smd rect
			(at -1.436 -0.33 90)
			(size 0.99 0.405)
			(layers "B.Cu" "B.Mask" "B.Paste")
			(net 522 "/Power/USBPD1_HV")
			(pinfunction "S")
			(pintype "passive")
		)
		(pad "4" smd rect
			(at -1.436 -0.988 90)
			(size 0.99 0.405)
			(layers "B.Cu" "B.Mask" "B.Paste")
			(net 1202 "Net-(Q24-G)")
			(pinfunction "G")
			(pintype "input")
		)
		(pad "5" smd custom
			(at 0.557 0 90)
			(size 1.725 2.235)
			(layers "B.Cu" "B.Mask" "B.Paste")
			(net 904 "+20V")
			(pinfunction "D")
			(pintype "passive")
			(zone_connect 2)
			(options
				(clearance outline)
				(anchor rect)
			)
			(primitives
				(gr_poly
					(pts
						(xy 0.8625 -0.1275) (xy 0.8625 0.1275) (xy 1.3725 0.1275) (xy 1.3725 0.5325) (xy 0.8625 0.5325)
						(xy 0.8625 0.7875) (xy 1.3725 0.7875) (xy 1.3725 1.195) (xy 0.6125 1.195) (xy 0.6125 -1.195) (xy 1.3725 -1.195)
						(xy 1.3725 -0.7875) (xy 0.8625 -0.7875) (xy 0.8625 -0.5325) (xy 1.3725 -0.5325) (xy 1.3725 -0.1275)
					)
					(width 0)
					(fill yes)
				)
			)
		)
	)
)
